# T6G (Grand Teton) — schematic netlist excerpt (pin names and nets, part order shuffled) for the footprints in the layout excerpt that follows; sources: Cadence DE-HDL packaged netlist, KiCad conversion of 04192023_DAF0TMB3IC0_F0TG_MB_C_brd_V02_OCP.brd

C2529  Q_CAP  22UF 4V 20% X6S  pkg C0402  page 70 : A = PVDDCR_SOC_P0 ; B = GND
C988  Q_CAP  22UF 4V 20% X6S  pkg C0402  page 301 : A = P0V9_CPU0_RT2_2A ; B = GND
PC123_4  Q_CAP  22UF 16V 20% X6S  pkg C0805  page 202 : A = SW_P12V_AUX_PVDDCR_CPU1_P0_FLT ; B = GND

(kicad_pcb
	(version 20260206)
	(generator "pcbnew")
	(generator_version "10.0")
	(general
		(thickness 1.6)
		(legacy_teardrops no)
	)
	(paper "A4")
	(title_block
		(title "04192023_DAF0TMB3IC0_F0TG_MB_C_brd_V02_OCP.brd")
		(comment 1 "Grand Teton / footprints 8105-8107 of 8354")
	)
	(layers
		(0 "F.Cu" signal "TOP")
		(4 "In1.Cu" signal "GND")
		(6 "In2.Cu" signal "IN1")
		(8 "In3.Cu" signal "GND1")
		(10 "In4.Cu" signal "IN2")
		(12 "In5.Cu" signal "GND2")
		(14 "In6.Cu" signal "IN3")
		(16 "In7.Cu" signal "GND3")
		(18 "In8.Cu" signal "VCC")
		(20 "In9.Cu" signal "VCC1")
		(22 "In10.Cu" signal "GND4")
		(24 "In11.Cu" signal "IN4")
		(26 "In12.Cu" signal "GND5")
		(28 "In13.Cu" signal "IN5")
		(30 "In14.Cu" signal "GND6")
		(32 "In15.Cu" signal "IN6")
		(34 "In16.Cu" signal "GND7")
		(2 "B.Cu" signal "BOTTOM")
		(9 "F.Adhes" user "F.Adhesive")
		(11 "B.Adhes" user "B.Adhesive")
		(13 "F.Paste" user "Package Geometry/Pastemask Top")
		(15 "B.Paste" user "Package Geometry/Pastemask Bottom")
		(5 "F.SilkS" user "Ref Des/Silkscreen Top")
		(7 "B.SilkS" user "Ref Des/Silkscreen Bottom")
		(1 "F.Mask" user "Board Geometry/Soldermask Top")
		(3 "B.Mask" user "Board Geometry/Soldermask Bottom")
		(17 "Dwgs.User" user "User.Drawings")
		(19 "Cmts.User" user "User.Comments")
		(21 "Eco1.User" user "User.Eco1")
		(23 "Eco2.User" user "User.Eco2")
		(25 "Edge.Cuts" user "Board Geometry/Outline")
		(27 "Margin" user)
		(31 "F.CrtYd" user "Package Geometry/Place Bound Top")
		(29 "B.CrtYd" user "Package Geometry/Place Bound Bottom")
		(35 "F.Fab" user "Ref Des/Assembly Top")
		(33 "B.Fab" user "Ref Des/Assembly Bottom")
	)
	(footprint ""
		(layer "B.Cu")
		(at 422.373044 -398.942052 90)
		(property "Reference" "C988"
			(at 0 0 90)
			(layer "B.SilkS")
			(hide yes)
			(effects
				(font
					(size 1.27 1.27)
				)
				(justify mirror)
			)
		)
		(property "Value" ""
			(at 0 0 90)
			(layer "B.Fab")
			(effects
				(font
					(size 1.27 1.27)
				)
				(justify mirror)
			)
		)
		(duplicate_pad_numbers_are_jumpers no)
		(fp_line
			(start 0.7874 -0.4064)
			(end -0.7874 -0.4064)
			(stroke
				(width 0.1524)
				(type default)
			)
			(layer "B.SilkS")
		)
		(fp_line
			(start -0.7874 -0.4064)
			(end -0.7874 0.4064)
			(stroke
				(width 0.1524)
				(type default)
			)
			(layer "B.SilkS")
		)
		(fp_line
			(start 0.7874 0.4064)
			(end 0.7874 -0.4064)
			(stroke
				(width 0.1524)
				(type default)
			)
			(layer "B.SilkS")
		)
		(fp_line
			(start -0.7874 0.4064)
			(end 0.7874 0.4064)
			(stroke
				(width 0.1524)
				(type default)
			)
			(layer "B.SilkS")
		)
		(fp_line
			(start 0.67945 -0.305054)
			(end 0.12065 -0.305054)
			(stroke
				(width 0.1)
				(type default)
			)
			(layer "B.Fab")
		)
		(fp_line
			(start 0.12065 -0.305054)
			(end 0.12065 -0.2794)
			(stroke
				(width 0.1)
				(type default)
			)
			(layer "B.Fab")
		)
		(fp_line
			(start -0.12065 -0.3048)
			(end -0.67945 -0.3048)
			(stroke
				(width 0.1)
				(type default)
			)
			(layer "B.Fab")
		)
		(fp_line
			(start -0.67945 -0.3048)
			(end -0.67945 0.3048)
			(stroke
				(width 0.1)
				(type default)
			)
			(layer "B.Fab")
		)
		(fp_line
			(start 0.12065 -0.2794)
			(end -0.12065 -0.2794)
			(stroke
				(width 0.1)
				(type default)
			)
			(layer "B.Fab")
		)
		(fp_line
			(start -0.12065 -0.2794)
			(end -0.12065 -0.3048)
			(stroke
				(width 0.1)
				(type default)
			)
			(layer "B.Fab")
		)
		(fp_line
			(start 0.12065 0.2794)
			(end 0.12065 0.3048)
			(stroke
				(width 0.1)
				(type default)
			)
			(layer "B.Fab")
		)
		(fp_line
			(start -0.120396 0.2794)
			(end 0.12065 0.2794)
			(stroke
				(width 0.1)
				(type default)
			)
			(layer "B.Fab")
		)
		(fp_line
			(start 0.67945 0.3048)
			(end 0.67945 -0.305054)
			(stroke
				(width 0.1)
				(type default)
			)
			(layer "B.Fab")
		)
		(fp_line
			(start 0.12065 0.3048)
			(end 0.67945 0.3048)
			(stroke
				(width 0.1)
				(type default)
			)
			(layer "B.Fab")
		)
		(fp_line
			(start -0.120396 0.3048)
			(end -0.120396 0.2794)
			(stroke
				(width 0.1)
				(type default)
			)
			(layer "B.Fab")
		)
		(fp_line
			(start -0.67945 0.3048)
			(end -0.120396 0.3048)
			(stroke
				(width 0.1)
				(type default)
			)
			(layer "B.Fab")
		)
		(pad "1" smd circle
			(at 0.40005 0 270)
			(size 0 0)
			(layers "B.Cu" "B.Mask" "B.Paste")
			(net "P0V9_CPU0_RT2_2A")
		)
		(pad "2" smd circle
			(at -0.40005 0 270)
			(size 0 0)
			(layers "B.Cu" "B.Mask" "B.Paste")
			(net "GND")
		)
	)
	(footprint ""
		(layer "B.Cu")
		(at 309.81777 -350.65589 -90)
		(property "Reference" "PC123_4"
			(at 0 0 90)
			(layer "B.SilkS")
			(hide yes)
			(effects
				(font
					(size 1.27 1.27)
				)
				(justify mirror)
			)
		)
		(property "Value" ""
			(at 0 0 90)
			(layer "B.Fab")
			(effects
				(font
					(size 1.27 1.27)
				)
				(justify mirror)
			)
		)
		(duplicate_pad_numbers_are_jumpers no)
		(fp_line
			(start -1.524 0.762)
			(end 1.524 0.762)
			(stroke
				(width 0.1524)
				(type default)
			)
			(layer "B.SilkS")
		)
		(fp_line
			(start 1.524 0.762)
			(end 1.524 -0.762)
			(stroke
				(width 0.1524)
				(type default)
			)
			(layer "B.SilkS")
		)
		(fp_line
			(start -1.524 -0.762)
			(end -1.524 0.762)
			(stroke
				(width 0.1524)
				(type default)
			)
			(layer "B.SilkS")
		)
		(fp_line
			(start 1.524 -0.762)
			(end -1.524 -0.762)
			(stroke
				(width 0.1524)
				(type default)
			)
			(layer "B.SilkS")
		)
		(fp_line
			(start -1.1049 0.724916)
			(end -1.1049 -0.724916)
			(stroke
				(width 0.1)
				(type default)
			)
			(layer "B.Fab")
		)
		(fp_line
			(start 1.1049 0.724916)
			(end -1.1049 0.724916)
			(stroke
				(width 0.1)
				(type default)
			)
			(layer "B.Fab")
		)
		(fp_line
			(start -1.1049 -0.724916)
			(end 1.1049 -0.724916)
			(stroke
				(width 0.1)
				(type default)
			)
			(layer "B.Fab")
		)
		(fp_line
			(start 1.1049 -0.724916)
			(end 1.1049 0.724916)
			(stroke
				(width 0.1)
				(type default)
			)
			(layer "B.Fab")
		)
		(pad "1" smd rect
			(at 0.889 0 270)
			(size 1.016 1.27)
			(layers "B.Cu" "B.Mask" "B.Paste")
			(net "SW_P12V_AUX_PVDDCR_CPU1_P0_FLT")
		)
		(pad "2" smd rect
			(at -0.889 0 270)
			(size 1.016 1.27)
			(layers "B.Cu" "B.Mask" "B.Paste")
			(net "GND")
		)
	)
	(footprint ""
		(layer "B.Cu")
		(at 370.408454 -261.046976)
		(property "Reference" "C2529"
			(at 0 0 0)
			(layer "B.SilkS")
			(hide yes)
			(effects
				(font
					(size 1.27 1.27)
				)
				(justify mirror)
			)
		)
		(property "Value" ""
			(at 0 0 0)
			(layer "B.Fab")
			(effects
				(font
					(size 1.27 1.27)
				)
				(justify mirror)
			)
		)
		(duplicate_pad_numbers_are_jumpers no)
		(fp_line
			(start -0.7874 -0.4064)
			(end -0.7874 0.4064)
			(stroke
				(width 0.1524)
				(type default)
			)
			(layer "B.SilkS")
		)
		(fp_line
			(start -0.7874 0.4064)
			(end 0.7874 0.4064)
			(stroke
				(width 0.1524)
				(type default)
			)
			(layer "B.SilkS")
		)
		(fp_line
			(start 0.7874 -0.4064)
			(end -0.7874 -0.4064)
			(stroke
				(width 0.1524)
				(type default)
			)
			(layer "B.SilkS")
		)
		(fp_line
			(start 0.7874 0.4064)
			(end 0.7874 -0.4064)
			(stroke
				(width 0.1524)
				(type default)
			)
			(layer "B.SilkS")
		)
		(fp_line
			(start -0.67945 -0.3048)
			(end -0.67945 0.3048)
			(stroke
				(width 0.1)
				(type default)
			)
			(layer "B.Fab")
		)
		(fp_line
			(start -0.67945 0.3048)
			(end -0.120396 0.3048)
			(stroke
				(width 0.1)
				(type default)
			)
			(layer "B.Fab")
		)
		(fp_line
			(start -0.12065 -0.3048)
			(end -0.67945 -0.3048)
			(stroke
				(width 0.1)
				(type default)
			)
			(layer "B.Fab")
		)
		(fp_line
			(start -0.12065 -0.2794)
			(end -0.12065 -0.3048)
			(stroke
				(width 0.1)
				(type default)
			)
			(layer "B.Fab")
		)
		(fp_line
			(start -0.120396 0.2794)
			(end 0.12065 0.2794)
			(stroke
				(width 0.1)
				(type default)
			)
			(layer "B.Fab")
		)
		(fp_line
			(start -0.120396 0.3048)
			(end -0.120396 0.2794)
			(stroke
				(width 0.1)
				(type default)
			)
			(layer "B.Fab")
		)
		(fp_line
			(start 0.12065 -0.305054)
			(end 0.12065 -0.2794)
			(stroke
				(width 0.1)
				(type default)
			)
			(layer "B.Fab")
		)
		(fp_line
			(start 0.12065 -0.2794)
			(end -0.12065 -0.2794)
			(stroke
				(width 0.1)
				(type default)
			)
			(layer "B.Fab")
		)
		(fp_line
			(start 0.12065 0.2794)
			(end 0.12065 0.3048)
			(stroke
				(width 0.1)
				(type default)
			)
			(layer "B.Fab")
		)
		(fp_line
			(start 0.12065 0.3048)
			(end 0.67945 0.3048)
			(stroke
				(width 0.1)
				(type default)
			)
			(layer "B.Fab")
		)
		(fp_line
			(start 0.67945 -0.305054)
			(end 0.12065 -0.305054)
			(stroke
				(width 0.1)
				(type default)
			)
			(layer "B.Fab")
		)
		(fp_line
			(start 0.67945 0.3048)
			(end 0.67945 -0.305054)
			(stroke
				(width 0.1)
				(type default)
			)
			(layer "B.Fab")
		)
		(pad "1" smd circle
			(at 0.40005 0 180)
			(size 0 0)
			(layers "B.Cu" "B.Mask" "B.Paste")
			(net "PVDDCR_SOC_P0")
		)
		(pad "2" smd circle
			(at -0.40005 0 180)
			(size 0 0)
			(layers "B.Cu" "B.Mask" "B.Paste")
			(net "GND")
		)
	)
)
